# S9S_MB_2U (Grand Teton) — schematic netlist excerpt (pin names and nets, part order shuffled) for the footprints in the layout excerpt that follows; sources: Cadence DE-HDL packaged netlist, KiCad conversion of 03242023_DA0F0TMBIJ0_F0T_Motherboard_J_brd_V01_OCP.brd

R3394  Q_RES  0 5% CHIP  pkg 0402LF  page 231 : A = SMB_IOEXP_3V3AUX_SDA_R ; B = SMB_IOEXP_3V3AUX_SDA
R1809  Q_RES  20K 1% CHIP  pkg 0402LF  page 198 : A = P3V3_AUX ; B = FM_ADR_MODE0

(kicad_pcb
	(version 20260206)
	(generator "pcbnew")
	(generator_version "10.0")
	(general
		(thickness 1.6)
		(legacy_teardrops no)
	)
	(paper "A4")
	(title_block
		(title "03242023_DA0F0TMBIJ0_F0T_Motherboard_J_brd_V01_OCP.brd")
		(comment 1 "Grand Teton / footprints 740-741 of 6105")
	)
	(layers
		(0 "F.Cu" signal "TOP")
		(4 "In1.Cu" signal "GND")
		(6 "In2.Cu" signal "IN1")
		(8 "In3.Cu" signal "GND1")
		(10 "In4.Cu" signal "IN2")
		(12 "In5.Cu" signal "GND2")
		(14 "In6.Cu" signal "IN3")
		(16 "In7.Cu" signal "GND3")
		(18 "In8.Cu" signal "VCC")
		(20 "In9.Cu" signal "VCC1")
		(22 "In10.Cu" signal "GND4")
		(24 "In11.Cu" signal "IN4")
		(26 "In12.Cu" signal "GND5")
		(28 "In13.Cu" signal "IN5")
		(30 "In14.Cu" signal "GND6")
		(32 "In15.Cu" signal "IN6")
		(34 "In16.Cu" signal "GND7")
		(2 "B.Cu" signal "BOTTOM")
		(9 "F.Adhes" user "F.Adhesive")
		(11 "B.Adhes" user "B.Adhesive")
		(13 "F.Paste" user "Package Geometry/Pastemask Top")
		(15 "B.Paste" user "Package Geometry/Pastemask Bottom")
		(5 "F.SilkS" user "Ref Des/Silkscreen Top")
		(7 "B.SilkS" user "Ref Des/Silkscreen Bottom")
		(1 "F.Mask" user "Board Geometry/Soldermask Top")
		(3 "B.Mask" user "Board Geometry/Soldermask Bottom")
		(17 "Dwgs.User" user "User.Drawings")
		(19 "Cmts.User" user "User.Comments")
		(21 "Eco1.User" user "User.Eco1")
		(23 "Eco2.User" user "User.Eco2")
		(25 "Edge.Cuts" user "Board Geometry/Outline")
		(27 "Margin" user)
		(31 "F.CrtYd" user "Package Geometry/Place Bound Top")
		(29 "B.CrtYd" user "Package Geometry/Place Bound Bottom")
		(35 "F.Fab" user "Ref Des/Assembly Top")
		(33 "B.Fab" user "Ref Des/Assembly Bottom")
	)
	(footprint ""
		(layer "F.Cu")
		(at 322.263516 -24.579072)
		(property "Reference" "R1809"
			(at 0 0 0)
			(layer "F.SilkS")
			(hide yes)
			(effects
				(font
					(size 1.27 1.27)
				)
			)
		)
		(property "Value" ""
			(at 0 0 0)
			(layer "F.Fab")
			(effects
				(font
					(size 1.27 1.27)
				)
			)
		)
		(duplicate_pad_numbers_are_jumpers no)
		(fp_line
			(start -0.7874 -0.4064)
			(end 0.7874 -0.4064)
			(stroke
				(width 0.1524)
				(type default)
			)
			(layer "F.SilkS")
		)
		(fp_line
			(start -0.7874 0.4064)
			(end -0.7874 -0.4064)
			(stroke
				(width 0.1524)
				(type default)
			)
			(layer "F.SilkS")
		)
		(fp_line
			(start 0.7874 -0.4064)
			(end 0.7874 0.4064)
			(stroke
				(width 0.1524)
				(type default)
			)
			(layer "F.SilkS")
		)
		(fp_line
			(start 0.7874 0.4064)
			(end -0.7874 0.4064)
			(stroke
				(width 0.1524)
				(type default)
			)
			(layer "F.SilkS")
		)
		(fp_line
			(start -0.67945 -0.305054)
			(end -0.12065 -0.305054)
			(stroke
				(width 0.1)
				(type default)
			)
			(layer "F.Fab")
		)
		(fp_line
			(start -0.67945 0.3048)
			(end -0.67945 -0.305054)
			(stroke
				(width 0.1)
				(type default)
			)
			(layer "F.Fab")
		)
		(fp_line
			(start -0.12065 -0.305054)
			(end -0.12065 -0.2794)
			(stroke
				(width 0.1)
				(type default)
			)
			(layer "F.Fab")
		)
		(fp_line
			(start -0.12065 -0.2794)
			(end 0.12065 -0.2794)
			(stroke
				(width 0.1)
				(type default)
			)
			(layer "F.Fab")
		)
		(fp_line
			(start -0.12065 0.2794)
			(end -0.12065 0.3048)
			(stroke
				(width 0.1)
				(type default)
			)
			(layer "F.Fab")
		)
		(fp_line
			(start -0.12065 0.3048)
			(end -0.67945 0.3048)
			(stroke
				(width 0.1)
				(type default)
			)
			(layer "F.Fab")
		)
		(fp_line
			(start 0.120396 0.2794)
			(end -0.12065 0.2794)
			(stroke
				(width 0.1)
				(type default)
			)
			(layer "F.Fab")
		)
		(fp_line
			(start 0.120396 0.3048)
			(end 0.120396 0.2794)
			(stroke
				(width 0.1)
				(type default)
			)
			(layer "F.Fab")
		)
		(fp_line
			(start 0.12065 -0.3048)
			(end 0.67945 -0.3048)
			(stroke
				(width 0.1)
				(type default)
			)
			(layer "F.Fab")
		)
		(fp_line
			(start 0.12065 -0.2794)
			(end 0.12065 -0.3048)
			(stroke
				(width 0.1)
				(type default)
			)
			(layer "F.Fab")
		)
		(fp_line
			(start 0.67945 -0.3048)
			(end 0.67945 0.3048)
			(stroke
				(width 0.1)
				(type default)
			)
			(layer "F.Fab")
		)
		(fp_line
			(start 0.67945 0.3048)
			(end 0.120396 0.3048)
			(stroke
				(width 0.1)
				(type default)
			)
			(layer "F.Fab")
		)
		(pad "1" smd circle
			(at -0.40005 0)
			(size 0 0)
			(layers "F.Cu" "F.Mask" "F.Paste")
			(net "P3V3_AUX")
		)
		(pad "2" smd circle
			(at 0.40005 0)
			(size 0 0)
			(layers "F.Cu" "F.Mask" "F.Paste")
			(net "FM_ADR_MODE0")
		)
	)
	(footprint ""
		(layer "F.Cu")
		(at 113.494312 -133.472682 180)
		(property "Reference" "R3394"
			(at 0 0 180)
			(layer "F.SilkS")
			(hide yes)
			(effects
				(font
					(size 1.27 1.27)
				)
			)
		)
		(property "Value" ""
			(at 0 0 180)
			(layer "F.Fab")
			(effects
				(font
					(size 1.27 1.27)
				)
			)
		)
		(duplicate_pad_numbers_are_jumpers no)
		(fp_line
			(start 0.7874 0.4064)
			(end -0.7874 0.4064)
			(stroke
				(width 0.1524)
				(type default)
			)
			(layer "F.SilkS")
		)
		(fp_line
			(start 0.7874 -0.4064)
			(end 0.7874 0.4064)
			(stroke
				(width 0.1524)
				(type default)
			)
			(layer "F.SilkS")
		)
		(fp_line
			(start -0.7874 0.4064)
			(end -0.7874 -0.4064)
			(stroke
				(width 0.1524)
				(type default)
			)
			(layer "F.SilkS")
		)
		(fp_line
			(start -0.7874 -0.4064)
			(end 0.7874 -0.4064)
			(stroke
				(width 0.1524)
				(type default)
			)
			(layer "F.SilkS")
		)
		(fp_line
			(start 0.67945 0.3048)
			(end 0.120396 0.3048)
			(stroke
				(width 0.1)
				(type default)
			)
			(layer "F.Fab")
		)
		(fp_line
			(start 0.67945 -0.3048)
			(end 0.67945 0.3048)
			(stroke
				(width 0.1)
				(type default)
			)
			(layer "F.Fab")
		)
		(fp_line
			(start 0.12065 -0.2794)
			(end 0.12065 -0.3048)
			(stroke
				(width 0.1)
				(type default)
			)
			(layer "F.Fab")
		)
		(fp_line
			(start 0.12065 -0.3048)
			(end 0.67945 -0.3048)
			(stroke
				(width 0.1)
				(type default)
			)
			(layer "F.Fab")
		)
		(fp_line
			(start 0.120396 0.3048)
			(end 0.120396 0.2794)
			(stroke
				(width 0.1)
				(type default)
			)
			(layer "F.Fab")
		)
		(fp_line
			(start 0.120396 0.2794)
			(end -0.12065 0.2794)
			(stroke
				(width 0.1)
				(type default)
			)
			(layer "F.Fab")
		)
		(fp_line
			(start -0.12065 0.3048)
			(end -0.67945 0.3048)
			(stroke
				(width 0.1)
				(type default)
			)
			(layer "F.Fab")
		)
		(fp_line
			(start -0.12065 0.2794)
			(end -0.12065 0.3048)
			(stroke
				(width 0.1)
				(type default)
			)
			(layer "F.Fab")
		)
		(fp_line
			(start -0.12065 -0.2794)
			(end 0.12065 -0.2794)
			(stroke
				(width 0.1)
				(type default)
			)
			(layer "F.Fab")
		)
		(fp_line
			(start -0.12065 -0.305054)
			(end -0.12065 -0.2794)
			(stroke
				(width 0.1)
				(type default)
			)
			(layer "F.Fab")
		)
		(fp_line
			(start -0.67945 0.3048)
			(end -0.67945 -0.305054)
			(stroke
				(width 0.1)
				(type default)
			)
			(layer "F.Fab")
		)
		(fp_line
			(start -0.67945 -0.305054)
			(end -0.12065 -0.305054)
			(stroke
				(width 0.1)
				(type default)
			)
			(layer "F.Fab")
		)
		(pad "1" smd circle
			(at -0.40005 0 180)
			(size 0 0)
			(layers "F.Cu" "F.Mask" "F.Paste")
			(net "SMB_IOEXP_3V3AUX_SDA_R")
		)
		(pad "2" smd circle
			(at 0.40005 0 180)
			(size 0 0)
			(layers "F.Cu" "F.Mask" "F.Paste")
			(net "SMB_IOEXP_3V3AUX_SDA")
		)
	)
)
